# S9S_MB_2U (Grand Teton) — schematic parts with pin connectivity, parts 5880–5880 of 6093; source: Cadence DE-HDL packaged netlist (pstxprt.dat, pstxnet.dat, pstchip.dat)

U2  SOCKET4677_AZIF0045P001C01CS  SOCKET4677_AZIF0045-P001C01CS IO  pkg SOCKET4677_82X64-5XA_H466  page 13  (pins 3587-3912 of 4677)
  EF63  VSS1392  POWER  = GND
  EF65  VSS1393  POWER  = GND
  EF67  VSS1395  POWER  = GND
  EF69  VSS1399  POWER  = GND
  EF71  VSS1402  POWER  = GND
  EF73  VSS1276  POWER  = GND
  EF75  VSS1277  POWER  = GND
  EF77  VSS1403  POWER  = GND
  EF79  VCCFA_EHV_FIVRA79  POWER  = PVCCFA_EHV_FIVRA_CPU0
  EF81  UPI3_RX_DN4  IN  = GND
  EF83  UPI3_RX_DP5  IN  = GND
  EF85  VSS1406  POWER  = GND
  EF87  VSS1407  POWER  = GND
  EF89  VSS1283  POWER  = GND
  EG3  UPI1_RX_DP1  IN  = UPI_CPU1_CPU0_P0P1_DP<1>
  EG5  VSS1290  POWER  = GND
  EG7  VSS1294  POWER  = GND
  EG9  VSS1414  POWER  = GND
  EG11  PE2_RX_DP15  IN  = P5E_CPU0_PE2_RX_DP<15>
  EG13  VSS1284  POWER  = GND
  EG15  PE2_TX_DP15  OUT  = P5E_CPU0_PE2_TX_DP<15>
  EG17  RSVD160  BI  = NC_CPU0_HBM0_VIEWDIG1
  EG19  DDR5_SB_DQ15  BI  = M_F_CPU0_SB_DQ<15>
  EG21  DDR5_SB_DQS_DP6  BI  = M_F_CPU0_SB_DQS_DP<6>
  EG23  DDR5_SB_DQ10  BI  = M_F_CPU0_SB_DQ<10>
  EG25  DDR4_SB_DQ7  BI  = M_E_CPU0_SB_DQ<7>
  EG27  DDR4_SB_DQS_DP5  BI  = M_E_CPU0_SB_DQS_DP<5>
  EG29  DDR4_SB_DQ2  BI  = M_E_CPU0_SB_DQ<2>
  EG31  DDR5_SB_ECC3  BI  = M_F_CPU0_SB_CB<3>
  EG33  DDR5_SB_DQS_DP4  BI  = M_F_CPU0_SB_DQS_DP<4>
  EG35  DDR5_SB_ECC6  BI  = M_F_CPU0_SB_CB<6>
  EG37  DDR5_SB_CS_N1  OUT  = M_F_CPU0_SB_CS_N<1>
  EG39  VSS1408  POWER  = GND
  EG41  DDR5_SB_CA3  OUT  = M_F_CPU0_SB_CA<3>
  EG43  DDR4_SB_CA0  OUT  = M_E_CPU0_SB_CA<0>
  EG45  DDR4_CLK_DP0  OUT  = M_E_CPU0_CLK_DP<0>
  EG48  DDR7_A_RSP0  IN  = M_H_CPU0_SA_RSP<0>
  EG50  DDR5_SA_CA5  OUT  = M_F_CPU0_SA_CA<5>
  EG52  VSS1291  POWER  = GND
  EG54  DDR5_SA_CS_N0  OUT  = M_F_CPU0_SA_CS_N<0>
  EG56  DDR5_SA_ECC7  BI  = M_F_CPU0_SA_CB<7>
  EG58  DDR5_SA_DQS_DP9  BI  = M_F_CPU0_SA_DQS_DP<9>
  EG60  DDR5_SA_ECC2  BI  = M_F_CPU0_SA_CB<2>
  EG62  DDR5_SA_DQ23  BI  = M_F_CPU0_SA_DQ<23>
  EG64  DDR5_SA_DQS_DP7  BI  = M_F_CPU0_SA_DQS_DP<7>
  EG66  DDR5_SA_DQ18  BI  = M_F_CPU0_SA_DQ<18>
  EG68  DDR4_SA_DQ15  BI  = M_E_CPU0_SA_DQ<15>
  EG70  DDR4_SA_DQS_DP6  BI  = M_E_CPU0_SA_DQS_DP<6>
  EG72  DDR4_SA_DQ10  BI  = M_E_CPU0_SA_DQ<10>
  EG74  DDR5_SA_DQ7  BI  = M_F_CPU0_SA_DQ<7>
  EG76  DDR5_SA_DQS_DP5  BI  = M_F_CPU0_SA_DQS_DP<5>
  EG78  DDR5_SA_DQ3  BI  = M_F_CPU0_SA_DQ<3>
  EG80  VCCFA_EHV_FIVRA80  POWER  = PVCCFA_EHV_FIVRA_CPU0
  EG82  VSS1410  POWER  = GND
  EG84  VSS1411  POWER  = GND
  EG86  VSS1412  POWER  = GND
  EG88  VSS1413  POWER  = GND
  EG90  VSS1415  POWER  = GND
  EH2  UPI1_RX_DN0  IN  = UPI_CPU1_CPU0_P0P1_DN<0>
  EH4  VSS1420  POWER  = GND
  EH6  VSS1318  POWER  = GND
  EH8  DDR6_SB_DQ25  BI  = M_G_CPU0_SB_DQ<25>
  EH10  PE2_RX_DN15  IN  = P5E_CPU0_PE2_RX_DN<15>
  EH12  VSS1302  POWER  = GND
  EH14  VSS1303  POWER  = GND
  EH16  VSS1416  POWER  = GND
  EH18  VSS1305  POWER  = GND
  EH20  DDR5_SB_DQ14  BI  = M_F_CPU0_SB_DQ<14>
  EH22  DDR5_SB_DQ11  BI  = M_F_CPU0_SB_DQ<11>
  EH24  VSS1417  POWER  = GND
  EH26  DDR4_SB_DQ6  BI  = M_E_CPU0_SB_DQ<6>
  EH28  DDR4_SB_DQ3  BI  = M_E_CPU0_SB_DQ<3>
  EH30  VSS1418  POWER  = GND
  EH32  DDR5_SB_ECC2  BI  = M_F_CPU0_SB_CB<2>
  EH34  DDR5_SB_ECC7  BI  = M_F_CPU0_SB_CB<7>
  EH36  VSS1419  POWER  = GND
  EH38  DDR5_SB_CS_N0  OUT  = M_F_CPU0_SB_CS_N<0>
  EH40  DDR5_SB_CA5  OUT  = M_F_CPU0_SB_CA<5>
  EH42  VSS1312  POWER  = GND
  EH44  DDR4_SB_CA1  OUT  = M_E_CPU0_SB_CA<1>
  EH47  DDR7_A_RSP1  IN  = M_H_CPU0_SA_RSP<1>
  EH49  VSS1421  POWER  = GND
  EH51  DDR5_SA_CA3  OUT  = M_F_CPU0_SA_CA<3>
  EH53  DDR5_SA_CS_N1  OUT  = M_F_CPU0_SA_CS_N<1>
  EH55  VSS1315  POWER  = GND
  EH57  DDR5_SA_ECC6  BI  = M_F_CPU0_SA_CB<6>
  EH59  DDR5_SA_ECC3  BI  = M_F_CPU0_SA_CB<3>
  EH61  VSS1319  POWER  = GND
  EH63  DDR5_SA_DQ22  BI  = M_F_CPU0_SA_DQ<22>
  EH65  DDR5_SA_DQ19  BI  = M_F_CPU0_SA_DQ<19>
  EH67  VSS1320  POWER  = GND
  EH69  DDR4_SA_DQ14  BI  = M_E_CPU0_SA_DQ<14>
  EH71  DDR4_SA_DQ11  BI  = M_E_CPU0_SA_DQ<11>
  EH73  VSS1422  POWER  = GND
  EH75  DDR5_SA_DQ6  BI  = M_F_CPU0_SA_DQ<6>
  EH77  DDR5_SA_DQ1  BI  = M_F_CPU0_SA_DQ<1>
  EH79  VSS1322  POWER  = GND
  EH81  VSS1423  POWER  = GND
  EH83  VSS1424  POWER  = GND
  EH85  UPI3_TX_DN0  OUT  = NC
  EH87  UPI3_TX_DP4  OUT  = NC
  EH89  PE3_RX_DN0  IN  = P5E_CPU0_PE3_RX_DN<0>
  EJ3  UPI1_RX_DP0  IN  = UPI_CPU1_CPU0_P0P1_DP<0>
  EJ5  DDR6_SB_DQ29  BI  = M_G_CPU0_SB_DQ<29>
  EJ7  VSS1444  POWER  = GND
  EJ9  VSS1450  POWER  = GND
  EJ11  VSS1325  POWER  = GND
  EJ13  VSS1425  POWER  = GND
  EJ15  VCCFA_EHV_FIVRA81  POWER  = PVCCFA_EHV_FIVRA_CPU0
  EJ17  VSS1328  POWER  = GND
  EJ19  VSS1426  POWER  = GND
  EJ21  DDR5_SB_DQS_DN6  BI  = M_F_CPU0_SB_DQS_DN<6>
  EJ23  VSS1428  POWER  = GND
  EJ25  VSS1331  POWER  = GND
  EJ27  DDR4_SB_DQS_DN5  BI  = M_E_CPU0_SB_DQS_DN<5>
  EJ29  VSS1429  POWER  = GND
  EJ31  VSS1430  POWER  = GND
  EJ33  DDR5_SB_DQS_DN4  BI  = M_F_CPU0_SB_DQS_DN<4>
  EJ35  VSS1334  POWER  = GND
  EJ37  VSS1431  POWER  = GND
  EJ39  DDR5_SB_PAR  OUT  = M_F_CPU0_SB_PAR
  EJ41  VSS1432  POWER  = GND
  EJ43  VSS1433  POWER  = GND
  EJ45  DDR4_CLK_DN0  OUT  = M_E_CPU0_CLK_DN<0>
  EJ48  VSS1434  POWER  = GND
  EJ50  VSS1435  POWER  = GND
  EJ52  DDR5_SA_CA1  OUT  = M_F_CPU0_SA_CA<1>
  EJ54  VSS1340  POWER  = GND
  EJ56  VSS1439  POWER  = GND
  EJ58  DDR5_SA_DQS_DN9  BI  = M_F_CPU0_SA_DQS_DN<9>
  EJ60  VSS1442  POWER  = GND
  EJ62  VSS1343  POWER  = GND
  EJ64  DDR5_SA_DQS_DN7  BI  = M_F_CPU0_SA_DQS_DN<7>
  EJ66  VSS1443  POWER  = GND
  EJ68  VSS1345  POWER  = GND
  EJ70  DDR4_SA_DQS_DN6  BI  = M_E_CPU0_SA_DQS_DN<6>
  EJ72  VSS1347  POWER  = GND
  EJ74  VSS1447  POWER  = GND
  EJ76  DDR5_SA_DQS_DN5  BI  = M_F_CPU0_SA_DQS_DN<5>
  EJ78  VSS1448  POWER  = GND
  EJ80  UPI3_RX_DN0  IN  = GND
  EJ82  UPI3_RX_DP3  IN  = GND
  EJ84  VCCFA_EHV_FIVRA82  POWER  = PVCCFA_EHV_FIVRA_CPU0
  EJ86  UPI3_TX_DN4  OUT  = NC
  EJ88  VSS1449  POWER  = GND
  EJ90  PE3_RX_DP0  IN  = P5E_CPU0_PE3_RX_DP<0>
  EK2  VSS1458  POWER  = GND
  EK4  VSS1466  POWER  = GND
  EK6  DDR6_SB_DQ28  BI  = M_G_CPU0_SB_DQ<28>
  EK8  DDR6_SB_DQ24  BI  = M_G_CPU0_SB_DQ<24>
  EK10  VSS1451  POWER  = GND
  EK12  DDR5_SB_DQS_DP2  BI  = M_F_CPU0_SB_DQS_DP<2>
  EK14  VSS1455  POWER  = GND
  EK16  VSS1355  POWER  = GND
  EK18  DDR4_SB_DQS_DN3  BI  = M_E_CPU0_SB_DQS_DN<3>
  EK20  VSS1357  POWER  = GND
  EK22  VSS1459  POWER  = GND
  EK24  DDR4_SB_DQS_DN2  BI  = M_E_CPU0_SB_DQS_DN<2>
  EK26  VSS1359  POWER  = GND
  EK28  VSS1460  POWER  = GND
  EK30  DDR4_SB_DQS_DN1  BI  = M_E_CPU0_SB_DQS_DN<1>
  EK32  VSS1461  POWER  = GND
  EK34  VSS1463  POWER  = GND
  EK36  DDR4_SB_DQS_DN9  BI  = M_E_CPU0_SB_DQS_DN<9>
  EK38  VSS1465  POWER  = GND
  EK40  VSS1469  POWER  = GND
  EK42  DDR4_SB_CA6  OUT  = M_E_CPU0_SB_CA<6>
  EK44  VSS1366  POWER  = GND
  EK47  VSS1470  POWER  = GND
  EK49  DDR4_SA_CA2  OUT  = M_E_CPU0_SA_CA<2>
  EK51  VSS1368  POWER  = GND
  EK53  VSS1369  POWER  = GND
  EK55  DDR4_SA_DQS_DP4  BI  = M_E_CPU0_SA_DQS_DP<4>
  EK57  VSS1471  POWER  = GND
  EK59  VSS1371  POWER  = GND
  EK61  DDR4_SA_DQS_DN3  BI  = M_E_CPU0_SA_DQS_DN<3>
  EK63  VSS1372  POWER  = GND
  EK65  VSS1472  POWER  = GND
  EK67  DDR4_SA_DQS_DN2  BI  = M_E_CPU0_SA_DQS_DN<2>
  EK69  VSS1473  POWER  = GND
  EK71  VSS1375  POWER  = GND
  EK73  DDR4_SA_DQ5  BI  = M_E_CPU0_SA_DQ<5>
  EK75  VSS1474  POWER  = GND
  EK77  VSS1377  POWER  = GND
  EK79  VSS1378  POWER  = GND
  EK81  UPI3_RX_DN3  IN  = GND
  EK83  VSS1379  POWER  = GND
  EK85  UPI3_TX_DP0  OUT  = NC
  EK87  UPI3_TX_DN5  OUT  = NC
  EK89  VSS1380  POWER  = GND
  EL3  VSS1479  POWER  = GND
  EL5  VSS1486  POWER  = GND
  EL7  VSS1396  POWER  = GND
  EL9  VSS1401  POWER  = GND
  EL11  DDR5_SB_DQ20  BI  = M_F_CPU0_SB_DQ<20>
  EL13  DDR5_SB_DQ17  BI  = M_F_CPU0_SB_DQ<17>
  EL15  VSS1381  POWER  = GND
  EL17  DDR4_SB_DQ28  BI  = M_E_CPU0_SB_DQ<28>
  EL19  DDR4_SB_DQ25  BI  = M_E_CPU0_SB_DQ<25>
  EL21  VSS1475  POWER  = GND
  EL23  DDR4_SB_DQ20  BI  = M_E_CPU0_SB_DQ<20>
  EL25  DDR4_SB_DQ17  BI  = M_E_CPU0_SB_DQ<17>
  EL27  VSS1477  POWER  = GND
  EL29  DDR4_SB_DQ12  BI  = M_E_CPU0_SB_DQ<12>
  EL31  DDR4_SB_DQ9  BI  = M_E_CPU0_SB_DQ<9>
  EL33  VSS1481  POWER  = GND
  EL35  DDR4_SB_ECC0  BI  = M_E_CPU0_SB_CB<0>
  EL37  DDR4_SB_ECC5  BI  = M_E_CPU0_SB_CB<5>
  EL39  VSS1483  POWER  = GND
  EL41  DDR4_SB_CS_N3  OUT  = M_E_CPU0_SB_CS_N<3>
  EL43  DDR4_SB_CA4  OUT  = M_E_CPU0_SB_CA<4>
  EL45  VSS1485  POWER  = GND
  EL48  DDR4_SA_CA3  OUT  = M_E_CPU0_SA_CA<3>
  EL50  DDR4_SA_CS_N3  OUT  = M_E_CPU0_SA_CS_N<3>
  EL52  VSS1391  POWER  = GND
  EL54  DDR4_SA_ECC4  BI  = M_E_CPU0_SA_CB<4>
  EL56  DDR4_SA_ECC1  BI  = M_E_CPU0_SA_CB<1>
  EL58  VSS1394  POWER  = GND
  EL60  DDR4_SA_DQ28  BI  = M_E_CPU0_SA_DQ<28>
  EL62  DDR4_SA_DQ25  BI  = M_E_CPU0_SA_DQ<25>
  EL64  VSS1488  POWER  = GND
  EL66  DDR4_SA_DQ22  BI  = M_E_CPU0_SA_DQ<22>
  EL68  DDR4_SA_DQS_DP2  BI  = M_E_CPU0_SA_DQS_DP<2>
  EL70  VSS1397  POWER  = GND
  EL72  VSS1398  POWER  = GND
  EL74  DDR4_SA_DQ4  BI  = M_E_CPU0_SA_DQ<4>
  EL76  VSS1489  POWER  = GND
  EL78  DDR4_SA_DQ0  BI  = M_E_CPU0_SA_DQ<0>
  EL80  UPI3_RX_DP0  IN  = GND
  EL82  UPI3_RX_DN2  IN  = GND
  EL84  UPI3_TX_DN1  OUT  = NC
  EL86  VSS1400  POWER  = GND
  EL88  UPI3_TX_DP5  OUT  = NC
  EM4  DDR6_SB_DQ31  BI  = M_G_CPU0_SB_DQ<31>
  EM6  DDR6_SB_DQS_DN8  BI  = M_G_CPU0_SB_DQS_DN<8>
  EM8  VSS1497  POWER  = GND
  EM10  DDR5_SB_DQ21  BI  = M_F_CPU0_SB_DQ<21>
  EM12  DDR5_SB_DQS_DN2  BI  = M_F_CPU0_SB_DQS_DN<2>
  EM14  DDR5_SB_DQ16  BI  = M_F_CPU0_SB_DQ<16>
  EM16  DDR4_SB_DQ29  BI  = M_E_CPU0_SB_DQ<29>
  EM18  DDR4_SB_DQS_DP3  BI  = M_E_CPU0_SB_DQS_DP<3>
  EM20  DDR4_SB_DQ24  BI  = M_E_CPU0_SB_DQ<24>
  EM22  DDR4_SB_DQ21  BI  = M_E_CPU0_SB_DQ<21>
  EM24  DDR4_SB_DQS_DP2  BI  = M_E_CPU0_SB_DQS_DP<2>
  EM26  DDR4_SB_DQ16  BI  = M_E_CPU0_SB_DQ<16>
  EM28  DDR4_SB_DQ13  BI  = M_E_CPU0_SB_DQ<13>
  EM30  DDR4_SB_DQS_DP1  BI  = M_E_CPU0_SB_DQS_DP<1>
  EM32  DDR4_SB_DQ8  BI  = M_E_CPU0_SB_DQ<8>
  EM34  DDR4_SB_ECC1  BI  = M_E_CPU0_SB_CB<1>
  EM36  DDR4_SB_DQS_DP9  BI  = M_E_CPU0_SB_DQS_DP<9>
  EM38  DDR4_SB_ECC4  BI  = M_E_CPU0_SB_CB<4>
  EM40  DDR4_SB_CS_N2  OUT  = M_E_CPU0_SB_CS_N<2>
  EM42  VSS1492  POWER  = GND
  EM44  DDR4_SB_CA2  OUT  = M_E_CPU0_SB_CA<2>
  EM47  DDR4_SA_CA4  OUT  = M_E_CPU0_SA_CA<4>
  EM49  VSS1405  POWER  = GND
  EM51  DDR4_SA_CS_N2  OUT  = M_E_CPU0_SA_CS_N<2>
  EM53  DDR4_SA_ECC5  BI  = M_E_CPU0_SA_CB<5>
  EM55  DDR4_SA_DQS_DN4  BI  = M_E_CPU0_SA_DQS_DN<4>
  EM57  DDR4_SA_ECC0  BI  = M_E_CPU0_SA_CB<0>
  EM59  DDR4_SA_DQ29  BI  = M_E_CPU0_SA_DQ<29>
  EM61  DDR4_SA_DQS_DP3  BI  = M_E_CPU0_SA_DQS_DP<3>
  EM63  DDR4_SA_DQ24  BI  = M_E_CPU0_SA_DQ<24>
  EM65  DDR4_SA_DQ21  BI  = M_E_CPU0_SA_DQ<21>
  EM67  DDR4_SA_DQS_DP7  BI  = M_E_CPU0_SA_DQS_DP<7>
  EM69  DDR4_SA_DQ17  BI  = M_E_CPU0_SA_DQ<17>
  EM71  DDR4_SA_DQ16  BI  = M_E_CPU0_SA_DQ<16>
  EM73  VSS1496  POWER  = GND
  EM75  DDR4_SA_DQS_DN5  BI  = M_E_CPU0_SA_DQS_DN<5>
  EM77  DDR4_SA_DQ1  BI  = M_E_CPU0_SA_DQ<1>
  EM79  VSS1409  POWER  = GND
  EM81  VSS1498  POWER  = GND
  EM83  VSS1499  POWER  = GND
  EM85  UPI3_TX_DP1  OUT  = NC
  EM87  UPI3_TX_DN3  OUT  = NC
  EN5  DDR6_SB_DQS_DP8  BI  = M_G_CPU0_SB_DQS_DP<8>
  EN7  DDR6_SB_DQS_DP3  BI  = M_G_CPU0_SB_DQS_DP<3>
  EN9  VSS1446  POWER  = GND
  EN11  VSS1500  POWER  = GND
  EN13  VSS1501  POWER  = GND
  EN15  VSS1503  POWER  = GND
  EN17  VSS1505  POWER  = GND
  EN19  VSS1506  POWER  = GND
  EN21  VSS1512  POWER  = GND
  EN23  VSS1513  POWER  = GND
  EN25  VSS1515  POWER  = GND
  EN27  VSS1517  POWER  = GND
  EN29  VSS1518  POWER  = GND
  EN31  VSS1520  POWER  = GND
  EN33  VSS1522  POWER  = GND
  EN35  VSS1524  POWER  = GND
  EN37  VSS1525  POWER  = GND
  EN39  VSS1427  POWER  = GND
  EN41  VSS1526  POWER  = GND
  EN43  VSS1528  POWER  = GND
  EN45  VSS1529  POWER  = GND
  EN48  VSS1530  POWER  = GND
  EN50  VSS1531  POWER  = GND
  EN52  VSS1533  POWER  = GND
  EN54  VSS1537  POWER  = GND
  EN56  VSS1539  POWER  = GND
  EN58  VSS1436  POWER  = GND
  EN60  VSS1437  POWER  = GND
  EN62  VSS1438  POWER  = GND
  EN64  VSS1540  POWER  = GND
  EN66  VSS1440  POWER  = GND
  EN68  DDR4_SA_DQS_DN7  BI  = M_E_CPU0_SA_DQS_DN<7>
  EN70  DDR4_SA_DQ18  BI  = M_E_CPU0_SA_DQ<18>
  EN72  VSS1441  POWER  = GND
  EN74  DDR4_SA_DQS_DP5  BI  = M_E_CPU0_SA_DQS_DP<5>
  EN76  DDR4_SA_DQS_DP0  BI  = M_E_CPU0_SA_DQS_DP<0>
  EN78  VSS1541  POWER  = GND
  EN80  VSS1542  POWER  = GND
  EN82  UPI3_RX_DP2  IN  = GND
  EN84  VCCFA_EHV_FIVRA83  POWER  = PVCCFA_EHV_FIVRA_CPU0
  EN86  UPI3_TX_DP2  OUT  = NC
  EN88  VSS1445  POWER  = GND
  EP4  DDR6_SB_DQ30  BI  = M_G_CPU0_SB_DQ<30>
  EP6  DDR6_SB_DQS_DN3  BI  = M_G_CPU0_SB_DQS_DN<3>
  EP8  DDR6_SB_DQ26  BI  = M_G_CPU0_SB_DQ<26>
  EP10  DDR5_SB_DQ23  BI  = M_F_CPU0_SB_DQ<23>
  EP12  DDR5_SB_DQS_DP7  BI  = M_F_CPU0_SB_DQS_DP<7>
  EP14  DDR5_SB_DQ18  BI  = M_F_CPU0_SB_DQ<18>
  EP16  DDR4_SB_DQ31  BI  = M_E_CPU0_SB_DQ<31>
  EP18  DDR4_SB_DQS_DP8  BI  = M_E_CPU0_SB_DQS_DP<8>
  EP20  DDR4_SB_DQ26  BI  = M_E_CPU0_SB_DQ<26>
